(kicad_pcb
	(version 20241229)
	(generator "pcbnew")
	(generator_version "9.0")
	(general
		(thickness 1.294)
		(legacy_teardrops no)
	)
	(paper "A3")
	(title_block
		(title "Kintex 410T devboard")
		(date "2024-04-03")
		(rev "1.1.2")
		(comment 9 "footprint 170 of 975 (U1), pads 659-722 of 900")
	)
	(layers
		(0 "F.Cu" mixed)
		(4 "In1.Cu" power)
		(6 "In2.Cu" power)
		(8 "In3.Cu" mixed)
		(10 "In4.Cu" power)
		(12 "In5.Cu" mixed)
		(14 "In6.Cu" power)
		(16 "In7.Cu" mixed)
		(18 "In8.Cu" power)
		(2 "B.Cu" mixed)
		(9 "F.Adhes" user "F.Adhesive")
		(11 "B.Adhes" user "B.Adhesive")
		(13 "F.Paste" user)
		(15 "B.Paste" user)
		(5 "F.SilkS" user "F.Silkscreen")
		(7 "B.SilkS" user "B.Silkscreen")
		(1 "F.Mask" user)
		(3 "B.Mask" user)
		(17 "Dwgs.User" user "User.Drawings")
		(19 "Cmts.User" user "User.Comments")
		(21 "Eco1.User" user "User.Eco1")
		(23 "Eco2.User" user "User.Eco2")
		(25 "Edge.Cuts" user)
		(27 "Margin" user)
		(31 "F.CrtYd" user "F.Courtyard")
		(29 "B.CrtYd" user "B.Courtyard")
		(35 "F.Fab" user)
		(33 "B.Fab" user)
	)
	(footprint "antmicro-footprints:BGA-900_31x31mm_Layout30x30_P1x1mm_FFG900"
		(locked yes)
		(layer "F.Cu")
		(at 200 130)
		(property "Reference" "U1"
			(at -15.74 -15.78 0)
			(layer "F.SilkS")
			(effects
				(font
					(size 0.7 0.7)
					(thickness 0.15)
				)
				(justify left bottom)
			)
		)
		(property "Value" "XC7K410T-2FFG900I"
			(at -4.436 17.635 0)
			(layer "F.Fab")
			(effects
				(font
					(size 0.7 0.7)
					(thickness 0.15)
				)
				(justify left bottom)
			)
		)
		(property "Description" "FPGA, Kintex-7, MMCM, PLL, 350 I/O's, 710 MHz, 406720 Cells, 970 mV to 1.03 V, FCBGA-900"
			(at 0 0 0)
			(layer "F.Fab")
			(hide yes)
			(effects
				(font
					(size 1.27 1.27)
					(thickness 0.15)
				)
			)
		)
		(property "Author" "Antmicro"
			(at 0 0 0)
			(layer "F.Fab")
			(hide yes)
			(effects
				(font
					(size 1 1)
					(thickness 0.15)
				)
			)
		)
		(property "License" "Apache-2.0"
			(at 0 0 0)
			(layer "F.Fab")
			(hide yes)
			(effects
				(font
					(size 1 1)
					(thickness 0.15)
				)
			)
		)
		(property "MPN" "XC7K410T-2FFG900I"
			(at 0 0 0)
			(layer "F.Fab")
			(hide yes)
			(effects
				(font
					(size 1 1)
					(thickness 0.15)
				)
			)
		)
		(property "Manufacturer" "AMD-Xilinx"
			(at 0 0 0)
			(layer "F.Fab")
			(hide yes)
			(effects
				(font
					(size 1 1)
					(thickness 0.15)
				)
			)
		)
		(sheetname "FPGA supply")
		(sheetfile "fpga-supply.kicad_sch")
		(attr smd)
		(pad "M29" smd circle
			(at 13.5 -3.5)
			(size 0.5 0.5)
			(property pad_prop_bga)
			(layers "F.Cu" "F.Mask" "F.Paste")
			(net 1249 "/USER_IO.A23")
			(pinfunction "IO_L15P_T2_DQS_15")
			(pintype "bidirectional")
			(die_length 16.261)
			(solder_mask_margin 0.02)
		)
		(pad "M30" smd circle
			(at 14.5 -3.5)
			(size 0.5 0.5)
			(property pad_prop_bga)
			(layers "F.Cu" "F.Mask" "F.Paste")
			(net 1254 "/USER_IO.A28")
			(pinfunction "IO_L15N_T2_DQS_ADV_B_15")
			(pintype "bidirectional")
			(die_length 16.654)
			(solder_mask_margin 0.02)
		)
		(pad "N1" smd circle
			(at -14.5 -2.5)
			(size 0.5 0.5)
			(property pad_prop_bga)
			(layers "F.Cu" "F.Mask" "F.Paste")
			(net 1 "GND")
			(pinfunction "GND")
			(pintype "passive")
			(solder_mask_margin 0.02)
		)
		(pad "N2" smd circle
			(at -13.5 -2.5)
			(size 0.5 0.5)
			(property pad_prop_bga)
			(layers "F.Cu" "F.Mask" "F.Paste")
			(net 1 "GND")
			(pinfunction "GND")
			(pintype "passive")
			(solder_mask_margin 0.02)
		)
		(pad "N3" smd circle
			(at -12.5 -2.5)
			(size 0.5 0.5)
			(property pad_prop_bga)
			(layers "F.Cu" "F.Mask" "F.Paste")
			(net 78 "/FMC+ HSPC/GTX116.TX1_N")
			(pinfunction "MGTXTXN1_116")
			(pintype "bidirectional")
			(die_length 11.433)
			(solder_mask_margin 0.02)
		)
		(pad "N4" smd circle
			(at -11.5 -2.5)
			(size 0.5 0.5)
			(property pad_prop_bga)
			(layers "F.Cu" "F.Mask" "F.Paste")
			(net 73 "/FMC+ HSPC/GTX116.TX1_P")
			(pinfunction "MGTXTXP1_116")
			(pintype "bidirectional")
			(die_length 11.366)
			(solder_mask_margin 0.02)
		)
		(pad "N5" smd circle
			(at -10.5 -2.5)
			(size 0.5 0.5)
			(property pad_prop_bga)
			(layers "F.Cu" "F.Mask" "F.Paste")
			(net 8 "+1V2_MGTAVTT")
			(pinfunction "MGTAVTT")
			(pintype "passive")
			(solder_mask_margin 0.02)
		)
		(pad "N6" smd circle
			(at -9.5 -2.5)
			(size 0.5 0.5)
			(property pad_prop_bga)
			(layers "F.Cu" "F.Mask" "F.Paste")
			(net 1 "GND")
			(pinfunction "GND")
			(pintype "passive")
			(solder_mask_margin 0.02)
		)
		(pad "N7" smd circle
			(at -8.5 -2.5)
			(size 0.5 0.5)
			(property pad_prop_bga)
			(layers "F.Cu" "F.Mask" "F.Paste")
			(net 600 "/FMC+ HSPC/GTX116.REFCLK1_N")
			(pinfunction "MGTREFCLK1N_116")
			(pintype "bidirectional")
			(die_length 8.657)
			(solder_mask_margin 0.02)
		)
		(pad "N8" smd circle
			(at -7.5 -2.5)
			(size 0.5 0.5)
			(property pad_prop_bga)
			(layers "F.Cu" "F.Mask" "F.Paste")
			(net 598 "/FMC+ HSPC/GTX116.REFCLK1_P")
			(pinfunction "MGTREFCLK1P_116")
			(pintype "bidirectional")
			(die_length 8.202)
			(solder_mask_margin 0.02)
		)
		(pad "N9" smd circle
			(at -6.5 -2.5)
			(size 0.5 0.5)
			(property pad_prop_bga)
			(layers "F.Cu" "F.Mask" "F.Paste")
			(net 1 "GND")
			(pinfunction "GND")
			(pintype "passive")
			(solder_mask_margin 0.02)
		)
		(pad "N10" smd circle
			(at -5.5 -2.5)
			(size 0.5 0.5)
			(property pad_prop_bga)
			(layers "F.Cu" "F.Mask" "F.Paste")
			(net 650 "+1V0")
			(pinfunction "VCCINT")
			(pintype "passive")
			(solder_mask_margin 0.02)
		)
		(pad "N11" smd circle
			(at -4.5 -2.5)
			(size 0.5 0.5)
			(property pad_prop_bga)
			(layers "F.Cu" "F.Mask" "F.Paste")
			(net 1 "GND")
			(pinfunction "GND")
			(pintype "passive")
			(solder_mask_margin 0.02)
		)
		(pad "N12" smd circle
			(at -3.5 -2.5)
			(size 0.5 0.5)
			(property pad_prop_bga)
			(layers "F.Cu" "F.Mask" "F.Paste")
			(net 650 "+1V0")
			(pinfunction "VCCINT")
			(pintype "passive")
			(solder_mask_margin 0.02)
		)
		(pad "N13" smd circle
			(at -2.5 -2.5)
			(size 0.5 0.5)
			(property pad_prop_bga)
			(layers "F.Cu" "F.Mask" "F.Paste")
			(net 1 "GND")
			(pinfunction "GND")
			(pintype "passive")
			(solder_mask_margin 0.02)
		)
		(pad "N14" smd circle
			(at -1.5 -2.5)
			(size 0.5 0.5)
			(property pad_prop_bga)
			(layers "F.Cu" "F.Mask" "F.Paste")
			(net 650 "+1V0")
			(pinfunction "VCCINT")
			(pintype "passive")
			(solder_mask_margin 0.02)
		)
		(pad "N15" smd circle
			(at -0.5 -2.5)
			(size 0.5 0.5)
			(property pad_prop_bga)
			(layers "F.Cu" "F.Mask" "F.Paste")
			(net 1 "GND")
			(pinfunction "GND")
			(pintype "passive")
			(solder_mask_margin 0.02)
		)
		(pad "N16" smd circle
			(at 0.5 -2.5)
			(size 0.5 0.5)
			(property pad_prop_bga)
			(layers "F.Cu" "F.Mask" "F.Paste")
			(net 650 "+1V0")
			(pinfunction "VCCBRAM")
			(pintype "bidirectional")
			(solder_mask_margin 0.02)
		)
		(pad "N17" smd circle
			(at 1.5 -2.5)
			(size 0.5 0.5)
			(property pad_prop_bga)
			(layers "F.Cu" "F.Mask" "F.Paste")
			(net 1 "GND")
			(pinfunction "GND")
			(pintype "passive")
			(solder_mask_margin 0.02)
		)
		(pad "N18" smd circle
			(at 2.5 -2.5)
			(size 0.5 0.5)
			(property pad_prop_bga)
			(layers "F.Cu" "F.Mask" "F.Paste")
			(net 650 "+1V0")
			(pinfunction "VCCINT")
			(pintype "passive")
			(solder_mask_margin 0.02)
		)
		(pad "N19" smd circle
			(at 3.5 -2.5)
			(size 0.5 0.5)
			(property pad_prop_bga)
			(layers "F.Cu" "F.Mask" "F.Paste")
			(net 1243 "/USER_IO.A15")
			(pinfunction "IO_L19P_T3_A22_15")
			(pintype "bidirectional")
			(die_length 10.222)
			(solder_mask_margin 0.02)
		)
		(pad "N20" smd circle
			(at 4.5 -2.5)
			(size 0.5 0.5)
			(property pad_prop_bga)
			(layers "F.Cu" "F.Mask" "F.Paste")
			(net 1342 "unconnected-(U1B-IO_L19N_T3_A21_VREF_15-PadN20)")
			(pinfunction "IO_L19N_T3_A21_VREF_15")
			(pintype "bidirectional+no_connect")
			(die_length 9.626)
			(solder_mask_margin 0.02)
		)
		(pad "N21" smd circle
			(at 5.5 -2.5)
			(size 0.5 0.5)
			(property pad_prop_bga)
			(layers "F.Cu" "F.Mask" "F.Paste")
			(net 1343 "unconnected-(U1B-IO_L20P_T3_A20_15-PadN21)")
			(pinfunction "IO_L20P_T3_A20_15")
			(pintype "bidirectional+no_connect")
			(die_length 9.801)
			(solder_mask_margin 0.02)
		)
		(pad "N22" smd circle
			(at 6.5 -2.5)
			(size 0.5 0.5)
			(property pad_prop_bga)
			(layers "F.Cu" "F.Mask" "F.Paste")
			(net 1344 "unconnected-(U1B-IO_L20N_T3_A19_15-PadN22)")
			(pinfunction "IO_L20N_T3_A19_15")
			(pintype "bidirectional+no_connect")
			(die_length 11.991)
			(solder_mask_margin 0.02)
		)
		(pad "N23" smd circle
			(at 7.5 -2.5)
			(size 0.5 0.5)
			(property pad_prop_bga)
			(layers "F.Cu" "F.Mask" "F.Paste")
			(net 2 "VCC_USR_A")
			(pinfunction "VCCO_15")
			(pintype "passive")
			(solder_mask_margin 0.02)
		)
		(pad "N24" smd circle
			(at 8.5 -2.5)
			(size 0.5 0.5)
			(property pad_prop_bga)
			(layers "F.Cu" "F.Mask" "F.Paste")
			(net 1345 "unconnected-(U1B-IO_L21N_T3_DQS_A18_15-PadN24)")
			(pinfunction "IO_L21N_T3_DQS_A18_15")
			(pintype "bidirectional+no_connect")
			(die_length 12.575)
			(solder_mask_margin 0.02)
		)
		(pad "N25" smd circle
			(at 9.5 -2.5)
			(size 0.5 0.5)
			(property pad_prop_bga)
			(layers "F.Cu" "F.Mask" "F.Paste")
			(net 1346 "unconnected-(U1B-IO_L18P_T2_A24_15-PadN25)")
			(pinfunction "IO_L18P_T2_A24_15")
			(pintype "bidirectional+no_connect")
			(die_length 14.113)
			(solder_mask_margin 0.02)
		)
		(pad "N26" smd circle
			(at 10.5 -2.5)
			(size 0.5 0.5)
			(property pad_prop_bga)
			(layers "F.Cu" "F.Mask" "F.Paste")
			(net 1263 "/USER_IO.A38")
			(pinfunction "IO_L18N_T2_A23_15")
			(pintype "bidirectional")
			(die_length 13.64)
			(solder_mask_margin 0.02)
		)
		(pad "N27" smd circle
			(at 11.5 -2.5)
			(size 0.5 0.5)
			(property pad_prop_bga)
			(layers "F.Cu" "F.Mask" "F.Paste")
			(net 1256 "/USER_IO.A30")
			(pinfunction "IO_L16P_T2_A28_15")
			(pintype "bidirectional")
			(die_length 13.775)
			(solder_mask_margin 0.02)
		)
		(pad "N28" smd circle
			(at 12.5 -2.5)
			(size 0.5 0.5)
			(property pad_prop_bga)
			(layers "F.Cu" "F.Mask" "F.Paste")
			(net 1 "GND")
			(pinfunction "GND")
			(pintype "passive")
			(solder_mask_margin 0.02)
		)
		(pad "N29" smd circle
			(at 13.5 -2.5)
			(size 0.5 0.5)
			(property pad_prop_bga)
			(layers "F.Cu" "F.Mask" "F.Paste")
			(net 1261 "/USER_IO.A36")
			(pinfunction "IO_L17P_T2_A26_15")
			(pintype "bidirectional")
			(die_length 16.115)
			(solder_mask_margin 0.02)
		)
		(pad "N30" smd circle
			(at 14.5 -2.5)
			(size 0.5 0.5)
			(property pad_prop_bga)
			(layers "F.Cu" "F.Mask" "F.Paste")
			(net 1250 "/USER_IO.A24")
			(pinfunction "IO_L17N_T2_A25_15")
			(pintype "bidirectional")
			(die_length 16.693)
			(solder_mask_margin 0.02)
		)
		(pad "P1" smd circle
			(at -14.5 -1.5)
			(size 0.5 0.5)
			(property pad_prop_bga)
			(layers "F.Cu" "F.Mask" "F.Paste")
			(net 82 "/FMC+ HSPC/GTX116.TX0_N")
			(pinfunction "MGTXTXN0_116")
			(pintype "bidirectional")
			(die_length 13.527)
			(solder_mask_margin 0.02)
		)
		(pad "P2" smd circle
			(at -13.5 -1.5)
			(size 0.5 0.5)
			(property pad_prop_bga)
			(layers "F.Cu" "F.Mask" "F.Paste")
			(net 80 "/FMC+ HSPC/GTX116.TX0_P")
			(pinfunction "MGTXTXP0_116")
			(pintype "bidirectional")
			(die_length 13.639)
			(solder_mask_margin 0.02)
		)
		(pad "P3" smd circle
			(at -12.5 -1.5)
			(size 0.5 0.5)
			(property pad_prop_bga)
			(layers "F.Cu" "F.Mask" "F.Paste")
			(net 8 "+1V2_MGTAVTT")
			(pinfunction "MGTAVTT")
			(pintype "passive")
			(solder_mask_margin 0.02)
		)
		(pad "P4" smd circle
			(at -11.5 -1.5)
			(size 0.5 0.5)
			(property pad_prop_bga)
			(layers "F.Cu" "F.Mask" "F.Paste")
			(net 1 "GND")
			(pinfunction "GND")
			(pintype "passive")
			(solder_mask_margin 0.02)
		)
		(pad "P5" smd circle
			(at -10.5 -1.5)
			(size 0.5 0.5)
			(property pad_prop_bga)
			(layers "F.Cu" "F.Mask" "F.Paste")
			(net 307 "/FMC+ HSPC/GTX116.RX2_N")
			(pinfunction "MGTXRXN2_116")
			(pintype "bidirectional")
			(die_length 12.032)
			(solder_mask_margin 0.02)
		)
		(pad "P6" smd circle
			(at -9.5 -1.5)
			(size 0.5 0.5)
			(property pad_prop_bga)
			(layers "F.Cu" "F.Mask" "F.Paste")
			(net 312 "/FMC+ HSPC/GTX116.RX2_P")
			(pinfunction "MGTXRXP2_116")
			(pintype "bidirectional")
			(die_length 12.187)
			(solder_mask_margin 0.02)
		)
		(pad "P7" smd circle
			(at -8.5 -1.5)
			(size 0.5 0.5)
			(property pad_prop_bga)
			(layers "F.Cu" "F.Mask" "F.Paste")
			(net 6 "+1V0_MGTAVCC")
			(pinfunction "MGTAVCC")
			(pintype "passive")
			(solder_mask_margin 0.02)
		)
		(pad "P8" smd circle
			(at -7.5 -1.5)
			(size 0.5 0.5)
			(property pad_prop_bga)
			(layers "F.Cu" "F.Mask" "F.Paste")
			(net 1 "GND")
			(pinfunction "GND")
			(pintype "passive")
			(solder_mask_margin 0.02)
		)
		(pad "P9" smd circle
			(at -6.5 -1.5)
			(size 0.5 0.5)
			(property pad_prop_bga)
			(layers "F.Cu" "F.Mask" "F.Paste")
			(net 1 "GND")
			(pinfunction "GND")
			(pintype "passive")
			(solder_mask_margin 0.02)
		)
		(pad "P10" smd circle
			(at -5.5 -1.5)
			(size 0.5 0.5)
			(property pad_prop_bga)
			(layers "F.Cu" "F.Mask" "F.Paste")
			(net 1 "GND")
			(pinfunction "GND")
			(pintype "passive")
			(solder_mask_margin 0.02)
		)
		(pad "P11" smd circle
			(at -4.5 -1.5)
			(size 0.5 0.5)
			(property pad_prop_bga)
			(layers "F.Cu" "F.Mask" "F.Paste")
			(net 650 "+1V0")
			(pinfunction "VCCINT")
			(pintype "passive")
			(solder_mask_margin 0.02)
		)
		(pad "P12" smd circle
			(at -3.5 -1.5)
			(size 0.5 0.5)
			(property pad_prop_bga)
			(layers "F.Cu" "F.Mask" "F.Paste")
			(net 1 "GND")
			(pinfunction "GND")
			(pintype "passive")
			(solder_mask_margin 0.02)
		)
		(pad "P13" smd circle
			(at -2.5 -1.5)
			(size 0.5 0.5)
			(property pad_prop_bga)
			(layers "F.Cu" "F.Mask" "F.Paste")
			(net 26 "+1V8")
			(pinfunction "VCCAUX")
			(pintype "bidirectional")
			(solder_mask_margin 0.02)
		)
		(pad "P14" smd circle
			(at -1.5 -1.5)
			(size 0.5 0.5)
			(property pad_prop_bga)
			(layers "F.Cu" "F.Mask" "F.Paste")
			(net 1 "GND")
			(pinfunction "GNDADC_0")
			(pintype "bidirectional")
			(solder_mask_margin 0.02)
		)
		(pad "P15" smd circle
			(at -0.5 -1.5)
			(size 0.5 0.5)
			(property pad_prop_bga)
			(layers "F.Cu" "F.Mask" "F.Paste")
			(net 622 "+1V85_ADC")
			(pinfunction "VCCADC_0")
			(pintype "bidirectional")
			(solder_mask_margin 0.02)
		)
		(pad "P16" smd circle
			(at 0.5 -1.5)
			(size 0.5 0.5)
			(property pad_prop_bga)
			(layers "F.Cu" "F.Mask" "F.Paste")
			(net 1 "GND")
			(pinfunction "GND")
			(pintype "passive")
			(solder_mask_margin 0.02)
		)
		(pad "P17" smd circle
			(at 1.5 -1.5)
			(size 0.5 0.5)
			(property pad_prop_bga)
			(layers "F.Cu" "F.Mask" "F.Paste")
			(net 650 "+1V0")
			(pinfunction "VCCINT")
			(pintype "passive")
			(solder_mask_margin 0.02)
		)
		(pad "P18" smd circle
			(at 2.5 -1.5)
			(size 0.5 0.5)
			(property pad_prop_bga)
			(layers "F.Cu" "F.Mask" "F.Paste")
			(net 1 "GND")
			(pinfunction "GND")
			(pintype "passive")
			(solder_mask_margin 0.02)
		)
		(pad "P19" smd circle
			(at 3.5 -1.5)
			(size 0.5 0.5)
			(property pad_prop_bga)
			(layers "F.Cu" "F.Mask" "F.Paste")
			(net 1347 "unconnected-(U1B-IO_25_15-PadP19)")
			(pinfunction "IO_25_15")
			(pintype "bidirectional+no_connect")
			(die_length 8.83)
			(solder_mask_margin 0.02)
		)
		(pad "P20" smd circle
			(at 4.5 -1.5)
			(size 0.5 0.5)
			(property pad_prop_bga)
			(layers "F.Cu" "F.Mask" "F.Paste")
			(net 2 "VCC_USR_A")
			(pinfunction "VCCO_15")
			(pintype "passive")
			(solder_mask_margin 0.02)
		)
		(pad "P21" smd circle
			(at 5.5 -1.5)
			(size 0.5 0.5)
			(property pad_prop_bga)
			(layers "F.Cu" "F.Mask" "F.Paste")
			(net 1236 "/USER_IO.A5")
			(pinfunction "IO_L22P_T3_A17_15")
			(pintype "bidirectional")
			(die_length 9.84)
			(solder_mask_margin 0.02)
		)
		(pad "P22" smd circle
			(at 6.5 -1.5)
			(size 0.5 0.5)
			(property pad_prop_bga)
			(layers "F.Cu" "F.Mask" "F.Paste")
			(net 1253 "/USER_IO.A27")
			(pinfunction "IO_L22N_T3_A16_15")
			(pintype "bidirectional")
			(die_length 9.806)
			(solder_mask_margin 0.02)
		)
		(pad "P23" smd circle
			(at 7.5 -1.5)
			(size 0.5 0.5)
			(property pad_prop_bga)
			(layers "F.Cu" "F.Mask" "F.Paste")
			(net 1348 "unconnected-(U1B-IO_L21P_T3_DQS_15-PadP23)")
			(pinfunction "IO_L21P_T3_DQS_15")
			(pintype "bidirectional+no_connect")
			(die_length 12.753)
			(solder_mask_margin 0.02)
		)
		(pad "P24" smd circle
			(at 8.5 -1.5)
			(size 0.5 0.5)
			(property pad_prop_bga)
			(layers "F.Cu" "F.Mask" "F.Paste")
			(net 38 "/FPGA Bank 14 & 15/SYSTEM_FLASH.DQ0")
			(pinfunction "IO_L1P_T0_D00_MOSI_14")
			(pintype "bidirectional")
			(die_length 11.124)
			(solder_mask_margin 0.02)
		)
		(pad "P25" smd circle
			(at 9.5 -1.5)
			(size 0.5 0.5)
			(property pad_prop_bga)
			(layers "F.Cu" "F.Mask" "F.Paste")
			(net 1 "GND")
			(pinfunction "GND")
			(pintype "passive")
			(solder_mask_margin 0.02)
		)
		(pad "P26" smd circle
			(at 10.5 -1.5)
			(size 0.5 0.5)
			(property pad_prop_bga)
			(layers "F.Cu" "F.Mask" "F.Paste")
			(net 564 "/DRAM + SRAM/SRAM.~{OE}")
			(pinfunction "IO_L10P_T1_D14_14")
			(pintype "bidirectional")
			(die_length 15.193)
			(solder_mask_margin 0.02)
		)
		(pad "P27" smd circle
			(at 11.5 -1.5)
			(size 0.5 0.5)
			(property pad_prop_bga)
			(layers "F.Cu" "F.Mask" "F.Paste")
			(net 664 "/DRAM + SRAM/SRAM.A5")
			(pinfunction "IO_L8P_T1_D11_14")
			(pintype "bidirectional")
			(die_length 15.077)
			(solder_mask_margin 0.02)
		)
		(pad "P28" smd circle
			(at 12.5 -1.5)
			(size 0.5 0.5)
			(property pad_prop_bga)
			(layers "F.Cu" "F.Mask" "F.Paste")
			(net 665 "/DRAM + SRAM/SRAM.A6")
			(pinfunction "IO_L8N_T1_D12_14")
			(pintype "bidirectional")
			(die_length 14.693)
			(solder_mask_margin 0.02)
		)
		(pad "P29" smd circle
			(at 13.5 -1.5)
			(size 0.5 0.5)
			(property pad_prop_bga)
			(layers "F.Cu" "F.Mask" "F.Paste")
			(net 666 "/DRAM + SRAM/SRAM.DQ3")
			(pinfunction "IO_L7P_T1_D09_14")
			(pintype "bidirectional")
			(die_length 16.815)
			(solder_mask_margin 0.02)
		)
		(pad "P30" smd circle
			(at 14.5 -1.5)
			(size 0.5 0.5)
			(property pad_prop_bga)
			(layers "F.Cu" "F.Mask" "F.Paste")
			(net 24 "+3V3")
			(pinfunction "VCCO_14")
			(pintype "bidirectional")
			(solder_mask_margin 0.02)
		)
		(pad "R1" smd circle
			(at -14.5 -0.5)
			(size 0.5 0.5)
			(property pad_prop_bga)
			(layers "F.Cu" "F.Mask" "F.Paste")
			(net 1 "GND")
			(pinfunction "GND")
			(pintype "passive")
			(solder_mask_margin 0.02)
		)
		(pad "R2" smd circle
			(at -13.5 -0.5)
			(size 0.5 0.5)
			(property pad_prop_bga)
			(layers "F.Cu" "F.Mask" "F.Paste")
			(net 1 "GND")
			(pinfunction "GND")
			(pintype "passive")
			(solder_mask_margin 0.02)
		)
	)
)
